# S9S_MB_2U (Grand Teton) — schematic netlist excerpt (pin names and nets, part order shuffled) for the footprints in the layout excerpt that follows; sources: Cadence DE-HDL packaged netlist, KiCad conversion of 03242023_DA0F0TMBIJ0_F0T_Motherboard_J_brd_V01_OCP.brd

R1898  Q_RES  100 1% CHIP  pkg 0402LF  page 154 : A = OCP_SFF_ISO_BIF2_EN ; B = GND
R3180  Q_RES  100 1% CHIP  pkg 0402LF  page 159 : A = OCP_V3_1_PRSNTA_R_N ; B = GND

(kicad_pcb
	(version 20260206)
	(generator "pcbnew")
	(generator_version "10.0")
	(general
		(thickness 1.6)
		(legacy_teardrops no)
	)
	(paper "A4")
	(title_block
		(title "03242023_DA0F0TMBIJ0_F0T_Motherboard_J_brd_V01_OCP.brd")
		(comment 1 "Grand Teton / footprints 5011-5012 of 6105")
	)
	(layers
		(0 "F.Cu" signal "TOP")
		(4 "In1.Cu" signal "GND")
		(6 "In2.Cu" signal "IN1")
		(8 "In3.Cu" signal "GND1")
		(10 "In4.Cu" signal "IN2")
		(12 "In5.Cu" signal "GND2")
		(14 "In6.Cu" signal "IN3")
		(16 "In7.Cu" signal "GND3")
		(18 "In8.Cu" signal "VCC")
		(20 "In9.Cu" signal "VCC1")
		(22 "In10.Cu" signal "GND4")
		(24 "In11.Cu" signal "IN4")
		(26 "In12.Cu" signal "GND5")
		(28 "In13.Cu" signal "IN5")
		(30 "In14.Cu" signal "GND6")
		(32 "In15.Cu" signal "IN6")
		(34 "In16.Cu" signal "GND7")
		(2 "B.Cu" signal "BOTTOM")
		(9 "F.Adhes" user "F.Adhesive")
		(11 "B.Adhes" user "B.Adhesive")
		(13 "F.Paste" user "Package Geometry/Pastemask Top")
		(15 "B.Paste" user "Package Geometry/Pastemask Bottom")
		(5 "F.SilkS" user "Ref Des/Silkscreen Top")
		(7 "B.SilkS" user "Ref Des/Silkscreen Bottom")
		(1 "F.Mask" user "Board Geometry/Soldermask Top")
		(3 "B.Mask" user "Board Geometry/Soldermask Bottom")
		(17 "Dwgs.User" user "User.Drawings")
		(19 "Cmts.User" user "User.Comments")
		(21 "Eco1.User" user "User.Eco1")
		(23 "Eco2.User" user "User.Eco2")
		(25 "Edge.Cuts" user "Board Geometry/Outline")
		(27 "Margin" user)
		(31 "F.CrtYd" user "Package Geometry/Place Bound Top")
		(29 "B.CrtYd" user "Package Geometry/Place Bound Bottom")
		(35 "F.Fab" user "Ref Des/Assembly Top")
		(33 "B.Fab" user "Ref Des/Assembly Bottom")
	)
	(footprint ""
		(layer "B.Cu")
		(at 60.468002 -8.319262 -90)
		(property "Reference" "R3180"
			(at 0 0 90)
			(layer "B.SilkS")
			(hide yes)
			(effects
				(font
					(size 1.27 1.27)
				)
				(justify mirror)
			)
		)
		(property "Value" ""
			(at 0 0 90)
			(layer "B.Fab")
			(effects
				(font
					(size 1.27 1.27)
				)
				(justify mirror)
			)
		)
		(duplicate_pad_numbers_are_jumpers no)
		(fp_line
			(start -0.7874 0.4064)
			(end 0.7874 0.4064)
			(stroke
				(width 0.1524)
				(type default)
			)
			(layer "B.SilkS")
		)
		(fp_line
			(start 0.7874 0.4064)
			(end 0.7874 -0.4064)
			(stroke
				(width 0.1524)
				(type default)
			)
			(layer "B.SilkS")
		)
		(fp_line
			(start -0.7874 -0.4064)
			(end -0.7874 0.4064)
			(stroke
				(width 0.1524)
				(type default)
			)
			(layer "B.SilkS")
		)
		(fp_line
			(start 0.7874 -0.4064)
			(end -0.7874 -0.4064)
			(stroke
				(width 0.1524)
				(type default)
			)
			(layer "B.SilkS")
		)
		(fp_line
			(start -0.67945 0.3048)
			(end -0.120396 0.3048)
			(stroke
				(width 0.1)
				(type default)
			)
			(layer "B.Fab")
		)
		(fp_line
			(start -0.120396 0.3048)
			(end -0.120396 0.2794)
			(stroke
				(width 0.1)
				(type default)
			)
			(layer "B.Fab")
		)
		(fp_line
			(start 0.12065 0.3048)
			(end 0.67945 0.3048)
			(stroke
				(width 0.1)
				(type default)
			)
			(layer "B.Fab")
		)
		(fp_line
			(start 0.67945 0.3048)
			(end 0.67945 -0.305054)
			(stroke
				(width 0.1)
				(type default)
			)
			(layer "B.Fab")
		)
		(fp_line
			(start -0.120396 0.2794)
			(end 0.12065 0.2794)
			(stroke
				(width 0.1)
				(type default)
			)
			(layer "B.Fab")
		)
		(fp_line
			(start 0.12065 0.2794)
			(end 0.12065 0.3048)
			(stroke
				(width 0.1)
				(type default)
			)
			(layer "B.Fab")
		)
		(fp_line
			(start -0.12065 -0.2794)
			(end -0.12065 -0.3048)
			(stroke
				(width 0.1)
				(type default)
			)
			(layer "B.Fab")
		)
		(fp_line
			(start 0.12065 -0.2794)
			(end -0.12065 -0.2794)
			(stroke
				(width 0.1)
				(type default)
			)
			(layer "B.Fab")
		)
		(fp_line
			(start -0.67945 -0.3048)
			(end -0.67945 0.3048)
			(stroke
				(width 0.1)
				(type default)
			)
			(layer "B.Fab")
		)
		(fp_line
			(start -0.12065 -0.3048)
			(end -0.67945 -0.3048)
			(stroke
				(width 0.1)
				(type default)
			)
			(layer "B.Fab")
		)
		(fp_line
			(start 0.12065 -0.305054)
			(end 0.12065 -0.2794)
			(stroke
				(width 0.1)
				(type default)
			)
			(layer "B.Fab")
		)
		(fp_line
			(start 0.67945 -0.305054)
			(end 0.12065 -0.305054)
			(stroke
				(width 0.1)
				(type default)
			)
			(layer "B.Fab")
		)
		(pad "1" smd circle
			(at 0.40005 0 90)
			(size 0 0)
			(layers "B.Cu" "B.Mask" "B.Paste")
			(net "OCP_V3_1_PRSNTA_R_N")
		)
		(pad "2" smd circle
			(at -0.40005 0 90)
			(size 0 0)
			(layers "B.Cu" "B.Mask" "B.Paste")
			(net "GND")
		)
	)
	(footprint ""
		(layer "B.Cu")
		(at 431.546 -24.094948 -90)
		(property "Reference" "R1898"
			(at 0 0 90)
			(layer "B.SilkS")
			(hide yes)
			(effects
				(font
					(size 1.27 1.27)
				)
				(justify mirror)
			)
		)
		(property "Value" ""
			(at 0 0 90)
			(layer "B.Fab")
			(effects
				(font
					(size 1.27 1.27)
				)
				(justify mirror)
			)
		)
		(duplicate_pad_numbers_are_jumpers no)
		(fp_line
			(start -0.7874 0.4064)
			(end 0.7874 0.4064)
			(stroke
				(width 0.1524)
				(type default)
			)
			(layer "B.SilkS")
		)
		(fp_line
			(start 0.7874 0.4064)
			(end 0.7874 -0.4064)
			(stroke
				(width 0.1524)
				(type default)
			)
			(layer "B.SilkS")
		)
		(fp_line
			(start -0.7874 -0.4064)
			(end -0.7874 0.4064)
			(stroke
				(width 0.1524)
				(type default)
			)
			(layer "B.SilkS")
		)
		(fp_line
			(start 0.7874 -0.4064)
			(end -0.7874 -0.4064)
			(stroke
				(width 0.1524)
				(type default)
			)
			(layer "B.SilkS")
		)
		(fp_line
			(start -0.67945 0.3048)
			(end -0.120396 0.3048)
			(stroke
				(width 0.1)
				(type default)
			)
			(layer "B.Fab")
		)
		(fp_line
			(start -0.120396 0.3048)
			(end -0.120396 0.2794)
			(stroke
				(width 0.1)
				(type default)
			)
			(layer "B.Fab")
		)
		(fp_line
			(start 0.12065 0.3048)
			(end 0.67945 0.3048)
			(stroke
				(width 0.1)
				(type default)
			)
			(layer "B.Fab")
		)
		(fp_line
			(start 0.67945 0.3048)
			(end 0.67945 -0.305054)
			(stroke
				(width 0.1)
				(type default)
			)
			(layer "B.Fab")
		)
		(fp_line
			(start -0.120396 0.2794)
			(end 0.12065 0.2794)
			(stroke
				(width 0.1)
				(type default)
			)
			(layer "B.Fab")
		)
		(fp_line
			(start 0.12065 0.2794)
			(end 0.12065 0.3048)
			(stroke
				(width 0.1)
				(type default)
			)
			(layer "B.Fab")
		)
		(fp_line
			(start -0.12065 -0.2794)
			(end -0.12065 -0.3048)
			(stroke
				(width 0.1)
				(type default)
			)
			(layer "B.Fab")
		)
		(fp_line
			(start 0.12065 -0.2794)
			(end -0.12065 -0.2794)
			(stroke
				(width 0.1)
				(type default)
			)
			(layer "B.Fab")
		)
		(fp_line
			(start -0.67945 -0.3048)
			(end -0.67945 0.3048)
			(stroke
				(width 0.1)
				(type default)
			)
			(layer "B.Fab")
		)
		(fp_line
			(start -0.12065 -0.3048)
			(end -0.67945 -0.3048)
			(stroke
				(width 0.1)
				(type default)
			)
			(layer "B.Fab")
		)
		(fp_line
			(start 0.12065 -0.305054)
			(end 0.12065 -0.2794)
			(stroke
				(width 0.1)
				(type default)
			)
			(layer "B.Fab")
		)
		(fp_line
			(start 0.67945 -0.305054)
			(end 0.12065 -0.305054)
			(stroke
				(width 0.1)
				(type default)
			)
			(layer "B.Fab")
		)
		(pad "1" smd circle
			(at 0.40005 0 90)
			(size 0 0)
			(layers "B.Cu" "B.Mask" "B.Paste")
			(net "OCP_SFF_ISO_BIF2_EN")
		)
		(pad "2" smd circle
			(at -0.40005 0 90)
			(size 0 0)
			(layers "B.Cu" "B.Mask" "B.Paste")
			(net "GND")
		)
	)
)
